FILE_TYPE=LIBRARY_PARTS;
primitive '5K1R2F-2-GP_SMD-RG';
  pin
    '1':
      PIN_NUMBER='(1)';
      PIN_TYPE='ANALOG';
      NO_LOAD_CHECK='Both';
      NO_IO_CHECK='Both';
      NO_ASSERT_CHECK='TRUE';
      NO_DIR_CHECK='TRUE';
      ALLOW_CONNECT='TRUE';
    '2':
      PIN_NUMBER='(2)';
      PIN_TYPE='ANALOG';
      NO_LOAD_CHECK='Both';
      NO_IO_CHECK='Both';
      NO_ASSERT_CHECK='TRUE';
      NO_DIR_CHECK='TRUE';
      ALLOW_CONNECT='TRUE';
  end_pin;
  body
    PART_NAME='5K1R2F-2-GP';
    BODY_NAME='5K1R2F-2-GP';
    PHYS_DES_PREFIX='R';
    CLASS='DISCRETE';
  end_body;
end_primitive;

END.
